(kicad_pcb
	(version 20260206)
	(generator "pcbnew")
	(generator_version "10.0")
	(general
		(thickness 1.6)
		(legacy_teardrops no)
	)
	(paper "A4")
	(title_block
		(title "01162023_DA0F0TEBIF0_F0T_Expander_BD_F_brd_V02_OCP.brd")
		(comment 1 "Grand Teton / footprints 3184-3189 of 9728")
	)
	(layers
		(0 "F.Cu" signal "TOP")
		(4 "In1.Cu" signal "GND")
		(6 "In2.Cu" signal "VCC")
		(8 "In3.Cu" signal "VCC1")
		(10 "In4.Cu" signal "GND1")
		(12 "In5.Cu" signal "IN1")
		(14 "In6.Cu" signal "GND2")
		(16 "In7.Cu" signal "IN2")
		(18 "In8.Cu" signal "GND3")
		(20 "In9.Cu" signal "IN3")
		(22 "In10.Cu" signal "GND4")
		(24 "In11.Cu" signal "IN4")
		(26 "In12.Cu" signal "GND5")
		(28 "In13.Cu" signal "IN5")
		(30 "In14.Cu" signal "GND6")
		(32 "In15.Cu" signal "IN6")
		(34 "In16.Cu" signal "GND7")
		(2 "B.Cu" signal "BOTTOM")
		(9 "F.Adhes" user "F.Adhesive")
		(11 "B.Adhes" user "B.Adhesive")
		(13 "F.Paste" user "Package Geometry/Pastemask Top")
		(15 "B.Paste" user "Package Geometry/Pastemask Bottom")
		(5 "F.SilkS" user "Ref Des/Silkscreen Top")
		(7 "B.SilkS" user "Ref Des/Silkscreen Bottom")
		(1 "F.Mask" user "Board Geometry/Soldermask Top")
		(3 "B.Mask" user "Board Geometry/Soldermask Bottom")
		(17 "Dwgs.User" user "User.Drawings")
		(19 "Cmts.User" user "User.Comments")
		(21 "Eco1.User" user "User.Eco1")
		(23 "Eco2.User" user "User.Eco2")
		(25 "Edge.Cuts" user "Board Geometry/Outline")
		(27 "Margin" user)
		(31 "F.CrtYd" user "Package Geometry/Place Bound Top")
		(29 "B.CrtYd" user "Package Geometry/Place Bound Bottom")
		(35 "F.Fab" user "Ref Des/Assembly Top")
		(33 "B.Fab" user "Ref Des/Assembly Bottom")
	)
	(footprint ""
		(layer "F.Cu")
		(at 103.167942 -114.833654 90)
		(property "Reference" "PR6867"
			(at 0 0 90)
			(layer "F.SilkS")
			(hide yes)
			(effects
				(font
					(size 1.27 1.27)
				)
			)
		)
		(property "Value" ""
			(at 0 0 90)
			(layer "F.Fab")
			(effects
				(font
					(size 1.27 1.27)
				)
			)
		)
		(duplicate_pad_numbers_are_jumpers no)
		(fp_line
			(start 1.2954 -0.5842)
			(end 1.2954 0.5842)
			(stroke
				(width 0.1524)
				(type default)
			)
			(layer "F.SilkS")
		)
		(fp_line
			(start -1.2954 -0.5842)
			(end 1.2954 -0.5842)
			(stroke
				(width 0.1524)
				(type default)
			)
			(layer "F.SilkS")
		)
		(fp_line
			(start 1.2954 0.5842)
			(end -1.2954 0.5842)
			(stroke
				(width 0.1524)
				(type default)
			)
			(layer "F.SilkS")
		)
		(fp_line
			(start -1.2954 0.5842)
			(end -1.2954 -0.5842)
			(stroke
				(width 0.1524)
				(type default)
			)
			(layer "F.SilkS")
		)
		(fp_line
			(start 0.8636 -0.4572)
			(end 0.8636 -0.406654)
			(stroke
				(width 0.1)
				(type default)
			)
			(layer "F.Fab")
		)
		(fp_line
			(start -0.8636 -0.4572)
			(end 0.8636 -0.4572)
			(stroke
				(width 0.1)
				(type default)
			)
			(layer "F.Fab")
		)
		(fp_line
			(start 1.1938 -0.406654)
			(end 1.1938 0.4064)
			(stroke
				(width 0.1)
				(type default)
			)
			(layer "F.Fab")
		)
		(fp_line
			(start 0.8636 -0.406654)
			(end 1.1938 -0.406654)
			(stroke
				(width 0.1)
				(type default)
			)
			(layer "F.Fab")
		)
		(fp_line
			(start -0.8636 -0.406654)
			(end -0.8636 -0.4572)
			(stroke
				(width 0.1)
				(type default)
			)
			(layer "F.Fab")
		)
		(fp_line
			(start -1.1938 -0.406654)
			(end -0.8636 -0.406654)
			(stroke
				(width 0.1)
				(type default)
			)
			(layer "F.Fab")
		)
		(fp_line
			(start 1.1938 0.4064)
			(end 0.8636 0.4064)
			(stroke
				(width 0.1)
				(type default)
			)
			(layer "F.Fab")
		)
		(fp_line
			(start 0.8636 0.4064)
			(end 0.8636 0.4572)
			(stroke
				(width 0.1)
				(type default)
			)
			(layer "F.Fab")
		)
		(fp_line
			(start -0.8636 0.4064)
			(end -1.1938 0.4064)
			(stroke
				(width 0.1)
				(type default)
			)
			(layer "F.Fab")
		)
		(fp_line
			(start -1.1938 0.4064)
			(end -1.1938 -0.406654)
			(stroke
				(width 0.1)
				(type default)
			)
			(layer "F.Fab")
		)
		(fp_line
			(start -0.8636 0.4318)
			(end -0.8636 0.4064)
			(stroke
				(width 0.1)
				(type default)
			)
			(layer "F.Fab")
		)
		(fp_line
			(start 0.8636 0.4572)
			(end -0.8636 0.4572)
			(stroke
				(width 0.1)
				(type default)
			)
			(layer "F.Fab")
		)
		(fp_line
			(start -0.8636 0.4572)
			(end -0.8636 0.4318)
			(stroke
				(width 0.1)
				(type default)
			)
			(layer "F.Fab")
		)
		(pad "1" smd rect
			(at -0.7366 0)
			(size 0.7112 0.8128)
			(layers "F.Cu" "F.Mask" "F.Paste")
			(net "P12V_NIC1_CO_AVIN_PD")
		)
		(pad "2" smd rect
			(at 0.7366 0)
			(size 0.7112 0.8128)
			(layers "F.Cu" "F.Mask" "F.Paste")
			(net "P12V_AUX")
		)
	)
	(footprint ""
		(layer "F.Cu")
		(at 109.136942 -116.230654 90)
		(property "Reference" "R5831"
			(at 0 0 90)
			(layer "F.SilkS")
			(hide yes)
			(effects
				(font
					(size 1.27 1.27)
				)
			)
		)
		(property "Value" ""
			(at 0 0 90)
			(layer "F.Fab")
			(effects
				(font
					(size 1.27 1.27)
				)
			)
		)
		(duplicate_pad_numbers_are_jumpers no)
		(fp_line
			(start 0.7874 -0.4064)
			(end 0.7874 0.4064)
			(stroke
				(width 0.1524)
				(type default)
			)
			(layer "F.SilkS")
		)
		(fp_line
			(start -0.7874 -0.4064)
			(end 0.7874 -0.4064)
			(stroke
				(width 0.1524)
				(type default)
			)
			(layer "F.SilkS")
		)
		(fp_line
			(start 0.7874 0.4064)
			(end -0.7874 0.4064)
			(stroke
				(width 0.1524)
				(type default)
			)
			(layer "F.SilkS")
		)
		(fp_line
			(start -0.7874 0.4064)
			(end -0.7874 -0.4064)
			(stroke
				(width 0.1524)
				(type default)
			)
			(layer "F.SilkS")
		)
		(fp_line
			(start -0.12065 -0.305054)
			(end -0.12065 -0.2794)
			(stroke
				(width 0.1)
				(type default)
			)
			(layer "F.Fab")
		)
		(fp_line
			(start -0.67945 -0.305054)
			(end -0.12065 -0.305054)
			(stroke
				(width 0.1)
				(type default)
			)
			(layer "F.Fab")
		)
		(fp_line
			(start 0.67945 -0.3048)
			(end 0.67945 0.3048)
			(stroke
				(width 0.1)
				(type default)
			)
			(layer "F.Fab")
		)
		(fp_line
			(start 0.12065 -0.3048)
			(end 0.67945 -0.3048)
			(stroke
				(width 0.1)
				(type default)
			)
			(layer "F.Fab")
		)
		(fp_line
			(start 0.12065 -0.2794)
			(end 0.12065 -0.3048)
			(stroke
				(width 0.1)
				(type default)
			)
			(layer "F.Fab")
		)
		(fp_line
			(start -0.12065 -0.2794)
			(end 0.12065 -0.2794)
			(stroke
				(width 0.1)
				(type default)
			)
			(layer "F.Fab")
		)
		(fp_line
			(start 0.120396 0.2794)
			(end -0.12065 0.2794)
			(stroke
				(width 0.1)
				(type default)
			)
			(layer "F.Fab")
		)
		(fp_line
			(start -0.12065 0.2794)
			(end -0.12065 0.3048)
			(stroke
				(width 0.1)
				(type default)
			)
			(layer "F.Fab")
		)
		(fp_line
			(start 0.67945 0.3048)
			(end 0.120396 0.3048)
			(stroke
				(width 0.1)
				(type default)
			)
			(layer "F.Fab")
		)
		(fp_line
			(start 0.120396 0.3048)
			(end 0.120396 0.2794)
			(stroke
				(width 0.1)
				(type default)
			)
			(layer "F.Fab")
		)
		(fp_line
			(start -0.12065 0.3048)
			(end -0.67945 0.3048)
			(stroke
				(width 0.1)
				(type default)
			)
			(layer "F.Fab")
		)
		(fp_line
			(start -0.67945 0.3048)
			(end -0.67945 -0.305054)
			(stroke
				(width 0.1)
				(type default)
			)
			(layer "F.Fab")
		)
		(pad "1" smd circle
			(at -0.40005 0 90)
			(size 0 0)
			(layers "F.Cu" "F.Mask" "F.Paste")
			(net "PWRGD_P12V_NIC1_CO")
		)
		(pad "2" smd circle
			(at 0.40005 0 90)
			(size 0 0)
			(layers "F.Cu" "F.Mask" "F.Paste")
			(net "PWRGD_P12V_NIC1_R")
		)
	)
	(footprint ""
		(layer "F.Cu")
		(at 39.280592 -135.815324)
		(property "Reference" "C33"
			(at 0 0 0)
			(layer "F.SilkS")
			(hide yes)
			(effects
				(font
					(size 1.27 1.27)
				)
			)
		)
		(property "Value" ""
			(at 0 0 0)
			(layer "F.Fab")
			(effects
				(font
					(size 1.27 1.27)
				)
			)
		)
		(duplicate_pad_numbers_are_jumpers no)
		(fp_line
			(start -0.299974 -0.150114)
			(end 0.299974 -0.150114)
			(stroke
				(width 0.1)
				(type default)
			)
			(layer "F.Fab")
		)
		(fp_line
			(start -0.299974 0.150114)
			(end -0.299974 -0.150114)
			(stroke
				(width 0.1)
				(type default)
			)
			(layer "F.Fab")
		)
		(fp_line
			(start 0.299974 -0.150114)
			(end 0.299974 0.150114)
			(stroke
				(width 0.1)
				(type default)
			)
			(layer "F.Fab")
		)
		(fp_line
			(start 0.299974 0.150114)
			(end -0.299974 0.150114)
			(stroke
				(width 0.1)
				(type default)
			)
			(layer "F.Fab")
		)
		(pad "1" smd rect
			(at -0.2667 0)
			(size 0.3048 0.381)
			(layers "F.Cu" "F.Mask" "F.Paste")
			(net "P5E_PEX0_STN1_TX_DN<31>")
		)
		(pad "2" smd rect
			(at 0.2667 0)
			(size 0.3048 0.381)
			(layers "F.Cu" "F.Mask" "F.Paste")
			(net "P5E_PEX0_STN1_TX_C_DN<31>")
		)
	)
	(footprint ""
		(layer "F.Cu")
		(at 393.8397 -343.952322 90)
		(property "Reference" "C757"
			(at 0 0 90)
			(layer "F.SilkS")
			(hide yes)
			(effects
				(font
					(size 1.27 1.27)
				)
			)
		)
		(property "Value" ""
			(at 0 0 90)
			(layer "F.Fab")
			(effects
				(font
					(size 1.27 1.27)
				)
			)
		)
		(duplicate_pad_numbers_are_jumpers no)
		(fp_line
			(start 0.299974 -0.150114)
			(end 0.299974 0.150114)
			(stroke
				(width 0.1)
				(type default)
			)
			(layer "F.Fab")
		)
		(fp_line
			(start -0.299974 -0.150114)
			(end 0.299974 -0.150114)
			(stroke
				(width 0.1)
				(type default)
			)
			(layer "F.Fab")
		)
		(fp_line
			(start 0.299974 0.150114)
			(end -0.299974 0.150114)
			(stroke
				(width 0.1)
				(type default)
			)
			(layer "F.Fab")
		)
		(fp_line
			(start -0.299974 0.150114)
			(end -0.299974 -0.150114)
			(stroke
				(width 0.1)
				(type default)
			)
			(layer "F.Fab")
		)
		(pad "1" smd rect
			(at -0.2667 0 90)
			(size 0.3048 0.381)
			(layers "F.Cu" "F.Mask" "F.Paste")
			(net "P5E_PEX3_STN5_TX_DN<82>")
		)
		(pad "2" smd rect
			(at 0.2667 0 90)
			(size 0.3048 0.381)
			(layers "F.Cu" "F.Mask" "F.Paste")
			(net "P5E_PEX3_STN5_TX_C_DN<82>")
		)
	)
	(footprint ""
		(layer "F.Cu")
		(at 69.83984 -70.52437 90)
		(property "Reference" "PC381"
			(at 0 0 90)
			(layer "F.SilkS")
			(hide yes)
			(effects
				(font
					(size 1.27 1.27)
				)
			)
		)
		(property "Value" ""
			(at 0 0 90)
			(layer "F.Fab")
			(effects
				(font
					(size 1.27 1.27)
				)
			)
		)
		(duplicate_pad_numbers_are_jumpers no)
		(fp_line
			(start 1.524 -0.762)
			(end 1.524 0.762)
			(stroke
				(width 0.1524)
				(type default)
			)
			(layer "F.SilkS")
		)
		(fp_line
			(start -1.524 -0.762)
			(end 1.524 -0.762)
			(stroke
				(width 0.1524)
				(type default)
			)
			(layer "F.SilkS")
		)
		(fp_line
			(start 1.524 0.762)
			(end -1.524 0.762)
			(stroke
				(width 0.1524)
				(type default)
			)
			(layer "F.SilkS")
		)
		(fp_line
			(start -1.524 0.762)
			(end -1.524 -0.762)
			(stroke
				(width 0.1524)
				(type default)
			)
			(layer "F.SilkS")
		)
		(fp_line
			(start 1.1049 -0.724916)
			(end -1.1049 -0.724916)
			(stroke
				(width 0.1)
				(type default)
			)
			(layer "F.Fab")
		)
		(fp_line
			(start -1.1049 -0.724916)
			(end -1.1049 0.724916)
			(stroke
				(width 0.1)
				(type default)
			)
			(layer "F.Fab")
		)
		(fp_line
			(start 1.1049 0.724916)
			(end 1.1049 -0.724916)
			(stroke
				(width 0.1)
				(type default)
			)
			(layer "F.Fab")
		)
		(fp_line
			(start -1.1049 0.724916)
			(end 1.1049 0.724916)
			(stroke
				(width 0.1)
				(type default)
			)
			(layer "F.Fab")
		)
		(pad "1" smd rect
			(at -0.889 0 270)
			(size 1.016 1.27)
			(layers "F.Cu" "F.Mask" "F.Paste")
			(net "P12V_SSD2_R")
		)
		(pad "2" smd rect
			(at 0.889 0 270)
			(size 1.016 1.27)
			(layers "F.Cu" "F.Mask" "F.Paste")
			(net "GND")
		)
	)
	(footprint ""
		(layer "F.Cu")
		(at 437.949848 -320.900044)
		(property "Reference" "H93"
			(at -7.113016 -7.203948 0)
			(unlocked yes)
			(layer "F.SilkS")
			(effects
				(font
					(size 0.7874 0.5842)
					(thickness 0.1524)
				)
				(justify left)
			)
		)
		(property "Value" ""
			(at 0 0 0)
			(layer "F.Fab")
			(effects
				(font
					(size 1.27 1.27)
				)
			)
		)
		(duplicate_pad_numbers_are_jumpers no)
		(fp_arc
			(start -7.999222 0.106172)
			(mid -0.053035 -7.999859)
			(end 7.999984 0)
			(stroke
				(width 0.1524)
				(type default)
			)
			(layer "F.SilkS")
		)
		(fp_arc
			(start 0.757174 7.963662)
			(mid -2.506424 7.596956)
			(end -5.347716 5.94995)
			(stroke
				(width 0.1524)
				(type default)
			)
			(layer "F.SilkS")
		)
		(fp_arc
			(start 7.999984 0)
			(mid 6.349365 4.866218)
			(end 2.079244 7.724648)
			(stroke
				(width 0.1524)
				(type default)
			)
			(layer "F.SilkS")
		)
		(fp_arc
			(start -7.997698 0.186436)
			(mid -0.093172 -7.999437)
			(end 7.999984 0)
			(stroke
				(width 0.1524)
				(type default)
			)
			(layer "B.SilkS")
		)
		(fp_arc
			(start 7.999984 0)
			(mid 3.365899 7.257353)
			(end -5.16763 6.106922)
			(stroke
				(width 0.1524)
				(type default)
			)
			(layer "B.SilkS")
		)
		(fp_circle
			(center 0 0)
			(end 7.999984 0)
			(stroke
				(width 0.1)
				(type default)
			)
			(fill no)
			(layer "B.Fab")
		)
		(fp_circle
			(center 0 0)
			(end 7.999984 0)
			(stroke
				(width 0.1)
				(type default)
			)
			(fill no)
			(layer "F.Fab")
		)
		(pad "" np_thru_hole circle
			(at 0 0)
			(size 4.5212 4.5212)
			(drill 4.5212)
			(layers "*.Cu" "*.Mask")
			(clearance 0.381)
			(thermal_gap 0.381)
		)
		(pad "2" thru_hole circle
			(at 3.6322 0)
			(size 0.762 0.762)
			(drill 0.5588)
			(layers "*.Cu" "*.Mask")
			(remove_unused_layers no)
			(net "GND")
			(clearance 0.1524)
			(thermal_gap 0.1524)
		)
		(pad "3" thru_hole circle
			(at 2.568448 -2.568448)
			(size 0.762 0.762)
			(drill 0.5588)
			(layers "*.Cu" "*.Mask")
			(remove_unused_layers no)
			(net "GND")
			(clearance 0.1524)
			(thermal_gap 0.1524)
		)
		(pad "4" thru_hole circle
			(at 0 -3.6322)
			(size 0.762 0.762)
			(drill 0.5588)
			(layers "*.Cu" "*.Mask")
			(remove_unused_layers no)
			(net "GND")
			(clearance 0.1524)
			(thermal_gap 0.1524)
		)
		(pad "5" thru_hole circle
			(at -2.568448 -2.568448)
			(size 0.762 0.762)
			(drill 0.5588)
			(layers "*.Cu" "*.Mask")
			(remove_unused_layers no)
			(net "GND")
			(clearance 0.1524)
			(thermal_gap 0.1524)
		)
		(pad "6" thru_hole circle
			(at -3.6322 0)
			(size 0.762 0.762)
			(drill 0.5588)
			(layers "*.Cu" "*.Mask")
			(remove_unused_layers no)
			(net "GND")
			(clearance 0.1524)
			(thermal_gap 0.1524)
		)
		(pad "7" thru_hole circle
			(at -2.568448 2.568448)
			(size 0.762 0.762)
			(drill 0.5588)
			(layers "*.Cu" "*.Mask")
			(remove_unused_layers no)
			(net "GND")
			(clearance 0.1524)
			(thermal_gap 0.1524)
		)
		(pad "8" thru_hole circle
			(at 0 3.6322)
			(size 0.762 0.762)
			(drill 0.5588)
			(layers "*.Cu" "*.Mask")
			(remove_unused_layers no)
			(net "GND")
			(clearance 0.1524)
			(thermal_gap 0.1524)
		)
		(pad "9" thru_hole circle
			(at 2.568448 2.568448)
			(size 0.762 0.762)
			(drill 0.5588)
			(layers "*.Cu" "*.Mask")
			(remove_unused_layers no)
			(net "GND")
			(clearance 0.1524)
			(thermal_gap 0.1524)
		)
		(zone
			(layer "F.Cu")
			(hatch none 0.5)
			(connect_pads
				(clearance 0)
			)
			(min_thickness 0.25)
			(keepout
				(tracks not_allowed)
				(vias allowed)
				(pads allowed)
				(copperpour not_allowed)
				(footprints allowed)
			)
			(placement
				(enabled no)
				(sheetname "")
			)
			(fill
				(thermal_gap 0.5)
				(thermal_bridge_width 0.5)
				(island_removal_mode 0)
			)
			(polygon
				(pts
					(arc
						(start 437.949848 -312.90006)
						(mid 429.949864 -320.900044)
						(end 437.949848 -328.900028)
					)
					(arc
						(start 437.949848 -325.649844)
						(mid 433.200048 -320.900044)
						(end 437.949848 -316.150244)
					)
				)
			)
		)
		(zone
			(layer "F.Cu")
			(hatch none 0.5)
			(connect_pads
				(clearance 0)
			)
			(min_thickness 0.25)
			(keepout
				(tracks not_allowed)
				(vias allowed)
				(pads allowed)
				(copperpour not_allowed)
				(footprints allowed)
			)
			(placement
				(enabled no)
				(sheetname "")
			)
			(fill
				(thermal_gap 0.5)
				(thermal_bridge_width 0.5)
				(island_removal_mode 0)
			)
			(polygon
				(pts
					(arc
						(start 437.949848 -312.90006)
						(mid 445.949832 -320.900044)
						(end 437.949848 -328.900028)
					)
					(arc
						(start 437.949848 -325.649844)
						(mid 442.699648 -320.900044)
						(end 437.949848 -316.150244)
					)
				)
			)
		)
		(zone
			(layers "F.Cu" "B.Cu" "In1.Cu" "In2.Cu" "In3.Cu" "In4.Cu" "In5.Cu" "In6.Cu"
				"In7.Cu" "In8.Cu" "In9.Cu" "In10.Cu" "In11.Cu" "In12.Cu" "In13.Cu" "In14.Cu"
				"In15.Cu" "In16.Cu"
			)
			(hatch none 0.5)
			(connect_pads
				(clearance 0)
			)
			(min_thickness 0.25)
			(keepout
				(tracks not_allowed)
				(vias allowed)
				(pads allowed)
				(copperpour not_allowed)
				(footprints allowed)
			)
			(placement
				(enabled no)
				(sheetname "")
			)
			(fill
				(thermal_gap 0.5)
				(thermal_bridge_width 0.5)
				(island_removal_mode 0)
			)
			(polygon
				(pts
					(arc
						(start 440.715908 -320.900044)
						(mid 435.183788 -320.900044)
						(end 440.715908 -320.900044)
					)
				)
			)
		)
		(zone
			(layer "B.Cu")
			(hatch none 0.5)
			(connect_pads
				(clearance 0)
			)
			(min_thickness 0.25)
			(keepout
				(tracks not_allowed)
				(vias allowed)
				(pads allowed)
				(copperpour not_allowed)
				(footprints allowed)
			)
			(placement
				(enabled no)
				(sheetname "")
			)
			(fill
				(thermal_gap 0.5)
				(thermal_bridge_width 0.5)
				(island_removal_mode 0)
			)
			(polygon
				(pts
					(arc
						(start 437.949848 -315.896244)
						(mid 432.946048 -320.900044)
						(end 437.949848 -325.903844)
					)
					(arc
						(start 437.949848 -325.421244)
						(mid 433.428648 -320.900044)
						(end 437.949848 -316.378844)
					)
				)
			)
		)
		(zone
			(layer "B.Cu")
			(hatch none 0.5)
			(connect_pads
				(clearance 0)
			)
			(min_thickness 0.25)
			(keepout
				(tracks not_allowed)
				(vias allowed)
				(pads allowed)
				(copperpour not_allowed)
				(footprints allowed)
			)
			(placement
				(enabled no)
				(sheetname "")
			)
			(fill
				(thermal_gap 0.5)
				(thermal_bridge_width 0.5)
				(island_removal_mode 0)
			)
			(polygon
				(pts
					(arc
						(start 437.949848 -315.896244)
						(mid 442.953648 -320.900044)
						(end 437.949848 -325.903844)
					)
					(arc
						(start 437.949848 -325.421244)
						(mid 442.471048 -320.900044)
						(end 437.949848 -316.378844)
					)
				)
			)
		)
	)
)
